# BASEBOARD_FAB2 (Tioga Pass) — schematic netlist excerpt (pin names and nets, part order shuffled) for the footprints in the layout excerpt that follows; sources: Cadence DE-HDL packaged netlist, KiCad conversion of Wiwynn_Tioga_Pass_MB.brd

Q8D1  NPN_DUAL  MBT3904 XSTR  pkg SSOPLF  page 89
  E(0)  = GND
  B(0)  = IRQ_DIMM_SAVE_LVT3
  C(0)  = IRQ_DIMM_SAVE_LVT3
  E(0)  = GND
  B(0)  = IRQ_DIMM_SAVE_R_N
  C(0)  = IRQ_DIMM_SAVE_LVT3_N

C7M2  CAP_A  47UF 4V 20% X5R  pkg 0603V  page 228 : A = PVDDQ_KLM ; B = GND
C2L41  CAP_A  0.01UF 25V 10% X7R  pkg 0402V  page 173 : A = SATA6G_P2_TX_C_DP ; B = SATA6G_PCH_PCIE_UP_SATA_TXP<2>

(kicad_pcb
	(version 20260206)
	(generator "pcbnew")
	(generator_version "10.0")
	(general
		(thickness 1.6)
		(legacy_teardrops no)
	)
	(paper "A4")
	(title_block
		(title "Wiwynn_Tioga_Pass_MB.brd")
		(comment 1 "Tioga Pass / footprints 3048-3050 of 4770")
	)
	(layers
		(0 "F.Cu" signal "TOP")
		(4 "In1.Cu" signal "L2GND")
		(6 "In2.Cu" signal "L3")
		(8 "In3.Cu" signal "L4GND")
		(10 "In4.Cu" signal "L5")
		(12 "In5.Cu" signal "L6GND")
		(14 "In6.Cu" signal "L7VCC")
		(16 "In7.Cu" signal "L8VCC")
		(18 "In8.Cu" signal "L9GND")
		(20 "In9.Cu" signal "L10")
		(22 "In10.Cu" signal "L11GND")
		(24 "In11.Cu" signal "L12")
		(26 "In12.Cu" signal "L13GND")
		(2 "B.Cu" signal "BOTTOM")
		(9 "F.Adhes" user "F.Adhesive")
		(11 "B.Adhes" user "B.Adhesive")
		(13 "F.Paste" user "Package Geometry/Pastemask Top")
		(15 "B.Paste" user "Package Geometry/Pastemask Bottom")
		(5 "F.SilkS" user "Ref Des/Silkscreen Top")
		(7 "B.SilkS" user "Ref Des/Silkscreen Bottom")
		(1 "F.Mask" user "Board Geometry/Soldermask Top")
		(3 "B.Mask" user "Board Geometry/Soldermask Bottom")
		(17 "Dwgs.User" user "User.Drawings")
		(19 "Cmts.User" user "User.Comments")
		(21 "Eco1.User" user "User.Eco1")
		(23 "Eco2.User" user "User.Eco2")
		(25 "Edge.Cuts" user "Board Geometry/Outline")
		(27 "Margin" user)
		(31 "F.CrtYd" user "Package Geometry/Place Bound Top")
		(29 "B.CrtYd" user "Package Geometry/Place Bound Bottom")
		(35 "F.Fab" user "Ref Des/Assembly Top")
		(33 "B.Fab" user "Ref Des/Assembly Bottom")
	)
	(footprint ""
		(layer "B.Cu")
		(at 425.196 -141.986)
		(property "Reference" "C2L41"
			(at 0 0 0)
			(layer "B.SilkS")
			(hide yes)
			(effects
				(font
					(size 1.27 1.27)
				)
				(justify mirror)
			)
		)
		(property "Value" ""
			(at 0 0 0)
			(layer "B.Fab")
			(effects
				(font
					(size 1.27 1.27)
				)
				(justify mirror)
			)
		)
		(duplicate_pad_numbers_are_jumpers no)
		(fp_poly
			(pts
				(xy -0.3048 -0.1016) (xy -0.3048 0.9906) (xy 0.3048 0.9906) (xy 0.3048 -0.1016)
			)
			(stroke
				(width 0)
				(type default)
			)
			(fill no)
			(layer "B.CrtYd")
		)
		(fp_line
			(start -0.3048 -0.1016)
			(end 0.3048 -0.1016)
			(stroke
				(width 0.1)
				(type default)
			)
			(layer "B.Fab")
		)
		(fp_line
			(start -0.3048 0.9906)
			(end -0.3048 -0.1016)
			(stroke
				(width 0.1)
				(type default)
			)
			(layer "B.Fab")
		)
		(fp_line
			(start 0.3048 -0.1016)
			(end 0.3048 0.9906)
			(stroke
				(width 0.1)
				(type default)
			)
			(layer "B.Fab")
		)
		(fp_line
			(start 0.3048 0.9906)
			(end -0.3048 0.9906)
			(stroke
				(width 0.1)
				(type default)
			)
			(layer "B.Fab")
		)
		(pad "1" smd rect
			(at 0 0 180)
			(size 0.508 0.508)
			(layers "B.Cu" "B.Mask" "B.Paste")
			(net "SATA6G_P2_TX_C_DP")
		)
		(pad "2" smd rect
			(at 0 0.889 180)
			(size 0.508 0.508)
			(layers "B.Cu" "B.Mask" "B.Paste")
			(net "SATA6G_PCH_PCIE_UP_SATA_TXP<2>")
		)
		(zone
			(layer "B.Cu")
			(hatch none 0.5)
			(connect_pads
				(clearance 0)
			)
			(min_thickness 0.25)
			(keepout
				(tracks allowed)
				(vias not_allowed)
				(pads allowed)
				(copperpour not_allowed)
				(footprints allowed)
			)
			(placement
				(enabled no)
				(sheetname "")
			)
			(fill
				(thermal_gap 0.5)
				(thermal_bridge_width 0.5)
				(island_removal_mode 0)
			)
			(polygon
				(pts
					(xy 425.45 -141.732) (xy 424.942 -141.732) (xy 424.942 -141.351) (xy 425.45 -141.351)
				)
			)
		)
		(zone
			(layer "B.Cu")
			(hatch none 0.5)
			(connect_pads
				(clearance 0)
			)
			(min_thickness 0.25)
			(keepout
				(tracks not_allowed)
				(vias allowed)
				(pads allowed)
				(copperpour not_allowed)
				(footprints allowed)
			)
			(placement
				(enabled no)
				(sheetname "")
			)
			(fill
				(thermal_gap 0.5)
				(thermal_bridge_width 0.5)
				(island_removal_mode 0)
			)
			(polygon
				(pts
					(xy 425.45 -141.351) (xy 424.942 -141.351) (xy 424.942 -141.732) (xy 425.45 -141.732)
				)
			)
		)
	)
	(footprint ""
		(layer "B.Cu")
		(at 107.8611 -135.4074 90)
		(property "Reference" "C7M2"
			(at -1.848866 0.752348 90)
			(unlocked yes)
			(layer "B.SilkS")
			(effects
				(font
					(size 1.27 0.9652)
					(thickness 0.1524)
				)
				(justify mirror)
			)
		)
		(property "Value" ""
			(at 0 0 90)
			(layer "B.Fab")
			(effects
				(font
					(size 1.27 1.27)
				)
				(justify mirror)
			)
		)
		(duplicate_pad_numbers_are_jumpers no)
		(fp_rect
			(start 0.500126 1.598422)
			(end -0.500126 -0.201422)
			(stroke
				(width 0)
				(type default)
			)
			(fill no)
			(layer "B.CrtYd")
		)
		(fp_line
			(start 0.500126 -0.201422)
			(end -0.500126 -0.201422)
			(stroke
				(width 0.1)
				(type default)
			)
			(layer "B.Fab")
		)
		(fp_line
			(start -0.500126 -0.201422)
			(end -0.500126 1.598422)
			(stroke
				(width 0.1)
				(type default)
			)
			(layer "B.Fab")
		)
		(fp_line
			(start 0.500126 1.598422)
			(end 0.500126 -0.201422)
			(stroke
				(width 0.1)
				(type default)
			)
			(layer "B.Fab")
		)
		(fp_line
			(start -0.500126 1.598422)
			(end 0.500126 1.598422)
			(stroke
				(width 0.1)
				(type default)
			)
			(layer "B.Fab")
		)
		(pad "1" smd rect
			(at 0 0)
			(size 0.889 0.9906)
			(layers "B.Cu" "B.Mask" "B.Paste")
			(net "PVDDQ_KLM")
		)
		(pad "2" smd rect
			(at 0 1.397)
			(size 0.889 0.9906)
			(layers "B.Cu" "B.Mask" "B.Paste")
			(net "GND")
		)
		(zone
			(layer "B.Cu")
			(hatch none 0.5)
			(connect_pads
				(clearance 0)
			)
			(min_thickness 0.25)
			(keepout
				(tracks allowed)
				(vias not_allowed)
				(pads allowed)
				(copperpour not_allowed)
				(footprints allowed)
			)
			(placement
				(enabled no)
				(sheetname "")
			)
			(fill
				(thermal_gap 0.5)
				(thermal_bridge_width 0.5)
				(island_removal_mode 0)
			)
			(polygon
				(pts
					(xy 108.8136 -135.9027) (xy 108.3056 -135.9027) (xy 108.3056 -134.9121) (xy 108.8136 -134.9121)
				)
			)
		)
		(zone
			(layer "B.Cu")
			(hatch none 0.5)
			(connect_pads
				(clearance 0)
			)
			(min_thickness 0.25)
			(keepout
				(tracks not_allowed)
				(vias allowed)
				(pads allowed)
				(copperpour not_allowed)
				(footprints allowed)
			)
			(placement
				(enabled no)
				(sheetname "")
			)
			(fill
				(thermal_gap 0.5)
				(thermal_bridge_width 0.5)
				(island_removal_mode 0)
			)
			(polygon
				(pts
					(xy 108.8136 -135.9027) (xy 108.3056 -135.9027) (xy 108.3056 -134.9121) (xy 108.8136 -134.9121)
				)
			)
		)
	)
	(footprint ""
		(layer "B.Cu")
		(at 313.424062 -27.727148 -90)
		(property "Reference" "Q8D1"
			(at 0 -1.2065 270)
			(unlocked yes)
			(layer "B.SilkS")
			(effects
				(font
					(size 1.27 0.9652)
					(thickness 0.1524)
				)
				(justify left mirror)
			)
		)
		(property "Value" ""
			(at 0 0 90)
			(layer "B.Fab")
			(effects
				(font
					(size 1.27 1.27)
				)
				(justify mirror)
			)
		)
		(duplicate_pad_numbers_are_jumpers no)
		(fp_circle
			(center 0.848614 -0.6477)
			(end 0.848614 -0.7747)
			(stroke
				(width 0.254)
				(type default)
			)
			(fill no)
			(layer "B.SilkS")
		)
		(fp_poly
			(pts
				(xy -0.21463 -0.450088) (xy -1.56337 -0.450088) (xy -1.56337 1.75006) (xy -0.21463 1.75006)
			)
			(stroke
				(width 0)
				(type default)
			)
			(fill no)
			(layer "B.CrtYd")
		)
		(fp_line
			(start -1.56337 1.75006)
			(end -0.21463 1.75006)
			(stroke
				(width 0.1)
				(type default)
			)
			(layer "B.Fab")
		)
		(fp_line
			(start -0.21463 1.75006)
			(end -0.21463 -0.450088)
			(stroke
				(width 0.1)
				(type default)
			)
			(layer "B.Fab")
		)
		(fp_line
			(start -1.56337 -0.450088)
			(end -1.56337 1.75006)
			(stroke
				(width 0.1)
				(type default)
			)
			(layer "B.Fab")
		)
		(fp_line
			(start -0.21463 -0.450088)
			(end -1.56337 -0.450088)
			(stroke
				(width 0.1)
				(type default)
			)
			(layer "B.Fab")
		)
		(fp_circle
			(center 0.848614 -0.6477)
			(end 0.848614 -0.7747)
			(stroke
				(width 0.254)
				(type default)
			)
			(fill no)
			(layer "B.Fab")
		)
		(pad "1" smd rect
			(at 0 0 90)
			(size 1.016 0.381)
			(layers "B.Cu" "B.Mask" "B.Paste")
			(net "GND")
		)
		(pad "2" smd rect
			(at 0 0.649986 90)
			(size 1.016 0.381)
			(layers "B.Cu" "B.Mask" "B.Paste")
			(net "IRQ_DIMM_SAVE_LVT3")
		)
		(pad "3" smd rect
			(at 0 1.299972 90)
			(size 1.016 0.381)
			(layers "B.Cu" "B.Mask" "B.Paste")
			(net "IRQ_DIMM_SAVE_LVT3")
		)
		(pad "4" smd rect
			(at -1.778 1.299972 90)
			(size 1.016 0.381)
			(layers "B.Cu" "B.Mask" "B.Paste")
			(net "GND")
		)
		(pad "5" smd rect
			(at -1.778 0.649986 90)
			(size 1.016 0.381)
			(layers "B.Cu" "B.Mask" "B.Paste")
			(net "IRQ_DIMM_SAVE_R_N")
		)
		(pad "6" smd rect
			(at -1.778 0 90)
			(size 1.016 0.381)
			(layers "B.Cu" "B.Mask" "B.Paste")
			(net "IRQ_DIMM_SAVE_LVT3_N")
		)
	)
)
